(kicad_pcb
	(version 20241229)
	(generator "pcbnew")
	(generator_version "9.0")
	(general
		(thickness 1.6642)
		(legacy_teardrops no)
	)
	(paper "A3")
	(title_block
		(title "PolarFire SoM")
		(date "2025-07-22")
		(rev "1.1.4")
		(company "Antmicro Ltd")
		(comment 1 "www.antmicro.com")
		(comment 9 "footprints 57-60 of 470")
	)
	(layers
		(0 "F.Cu" mixed)
		(4 "In1.Cu" power)
		(6 "In2.Cu" signal)
		(8 "In3.Cu" power)
		(10 "In4.Cu" signal)
		(12 "In5.Cu" power)
		(14 "In6.Cu" power)
		(16 "In7.Cu" signal)
		(18 "In8.Cu" power)
		(20 "In9.Cu" signal)
		(22 "In10.Cu" power)
		(24 "In11.Cu" signal)
		(26 "In12.Cu" signal)
		(2 "B.Cu" mixed)
		(9 "F.Adhes" user "F.Adhesive")
		(11 "B.Adhes" user "B.Adhesive")
		(13 "F.Paste" user)
		(15 "B.Paste" user)
		(5 "F.SilkS" user "F.Silkscreen")
		(7 "B.SilkS" user "B.Silkscreen")
		(1 "F.Mask" user)
		(3 "B.Mask" user)
		(17 "Dwgs.User" user "User.Drawings")
		(19 "Cmts.User" user "User.Comments")
		(21 "Eco1.User" user "User.Eco1")
		(23 "Eco2.User" user "User.Eco2")
		(25 "Edge.Cuts" user)
		(27 "Margin" user)
		(31 "F.CrtYd" user "F.Courtyard")
		(29 "B.CrtYd" user "B.Courtyard")
		(35 "F.Fab" user)
		(33 "B.Fab" user)
	)
	(footprint "antmicro-footprints:C_0402_1005Metric"
		(layer "F.Cu")
		(at 218.21 155.115 180)
		(descr "Capacitor SMD 0402")
		(tags "capacitor SMD 0402")
		(property "Reference" "C53"
			(at 2.86 -0.495 0)
			(layer "F.SilkS")
			(effects
				(font
					(size 0.7 0.7)
					(thickness 0.15)
				)
				(justify right bottom)
			)
		)
		(property "Value" "C_100n_0402"
			(at -1.022927 2.155213 0)
			(layer "F.Fab")
			(hide yes)
			(effects
				(font
					(size 0.7 0.7)
					(thickness 0.15)
				)
				(justify right bottom)
			)
		)
		(property "Datasheet" "https://www.murata.com/products/productdetail?partno=GRM155R61H104KE14%23"
			(at 0 0 180)
			(layer "F.Fab")
			(hide yes)
			(effects
				(font
					(size 1.27 1.27)
					(thickness 0.15)
				)
			)
		)
		(property "Description" "SMD Multilayer Ceramic Capacitor, 0.1 µF, 50 V, 0402 [1005 Metric], ± 10%, X5R, GRM Series"
			(at 0 0 180)
			(layer "F.Fab")
			(hide yes)
			(effects
				(font
					(size 1.27 1.27)
					(thickness 0.15)
				)
			)
		)
		(property "Author" "Antmicro"
			(at 436.42 310.23 0)
			(layer "F.Fab")
			(hide yes)
			(effects
				(font
					(size 1 1)
					(thickness 0.15)
				)
			)
		)
		(property "Dielectric" "X5R"
			(at 436.42 310.23 0)
			(layer "F.Fab")
			(hide yes)
			(effects
				(font
					(size 1 1)
					(thickness 0.15)
				)
			)
		)
		(property "License" "Apache-2.0"
			(at 436.42 310.23 0)
			(layer "F.Fab")
			(hide yes)
			(effects
				(font
					(size 1 1)
					(thickness 0.15)
				)
			)
		)
		(property "MPN" "GRM155R61H104KE14D"
			(at 436.42 310.23 0)
			(layer "F.Fab")
			(hide yes)
			(effects
				(font
					(size 1 1)
					(thickness 0.15)
				)
			)
		)
		(property "Manufacturer" "Murata"
			(at 436.42 310.23 0)
			(layer "F.Fab")
			(hide yes)
			(effects
				(font
					(size 1 1)
					(thickness 0.15)
				)
			)
		)
		(property "Public" ""
			(at 436.42 310.23 0)
			(layer "F.Fab")
			(hide yes)
			(effects
				(font
					(size 1 1)
					(thickness 0.15)
				)
			)
		)
		(property "Val" "100n"
			(at 436.42 310.23 0)
			(layer "F.Fab")
			(hide yes)
			(effects
				(font
					(size 1 1)
					(thickness 0.15)
				)
			)
		)
		(property "Voltage" "50V"
			(at 436.42 310.23 0)
			(layer "F.Fab")
			(hide yes)
			(effects
				(font
					(size 1 1)
					(thickness 0.15)
				)
			)
		)
		(sheetname "/PCIe/")
		(sheetfile "pcie.kicad_sch")
		(attr smd)
		(fp_rect
			(start -0.925 -0.47)
			(end 0.925 0.47)
			(stroke
				(width 0.05)
				(type default)
			)
			(fill no)
			(layer "F.CrtYd")
		)
		(fp_line
			(start 0.504 0.248)
			(end -0.494 0.248)
			(stroke
				(width 0.15)
				(type solid)
			)
			(layer "F.Fab")
		)
		(fp_line
			(start 0.504 -0.25)
			(end 0.504 0.248)
			(stroke
				(width 0.15)
				(type solid)
			)
			(layer "F.Fab")
		)
		(fp_line
			(start -0.494 0.248)
			(end -0.494 -0.25)
			(stroke
				(width 0.15)
				(type solid)
			)
			(layer "F.Fab")
		)
		(fp_line
			(start -0.494 -0.25)
			(end 0.504 -0.25)
			(stroke
				(width 0.15)
				(type solid)
			)
			(layer "F.Fab")
		)
		(fp_text user "License: Apache-2.0"
			(at -0.939 5.799 180)
			(layer "F.Fab")
			(effects
				(font
					(size 0.7 0.7)
					(thickness 0.15)
				)
				(justify left bottom)
			)
		)
		(fp_text user "${REFERENCE}"
			(at -0.939 4.599 180)
			(layer "F.Fab")
			(effects
				(font
					(size 0.7 0.7)
					(thickness 0.15)
				)
				(justify left bottom)
			)
		)
		(fp_text user "Author: Antmicro"
			(at -0.939 3.399 180)
			(layer "F.Fab")
			(effects
				(font
					(size 0.7 0.7)
					(thickness 0.15)
				)
				(justify left bottom)
			)
		)
		(pad "1" smd roundrect
			(at -0.48 0 180)
			(size 0.59 0.64)
			(layers "F.Cu" "F.Mask" "F.Paste")
			(roundrect_rratio 0.25)
			(net 314 "Net-(U17-CLK1-)")
			(pintype "passive")
		)
		(pad "2" smd roundrect
			(at 0.48 0 180)
			(size 0.59 0.64)
			(layers "F.Cu" "F.Mask" "F.Paste")
			(roundrect_rratio 0.25)
			(net 4 "/Bottom Connector/PCIE.CLK_N")
			(pintype "passive")
		)
	)
	(footprint "antmicro-footprints:Oscillator_SMD_ECS_2016MV_2x1.6x0.85mm"
		(layer "F.Cu")
		(at 222.2168 117.3457 180)
		(property "Reference" "Y2"
			(at -2.0232 0.0557 90)
			(layer "F.SilkS")
			(effects
				(font
					(size 0.7 0.7)
					(thickness 0.15)
				)
				(justify left bottom)
			)
		)
		(property "Value" "Oscillator_25MHz_ESC_2016MV"
			(at 0 2.2 0)
			(layer "F.Fab")
			(hide yes)
			(effects
				(font
					(size 0.7 0.7)
					(thickness 0.15)
				)
				(justify right bottom)
			)
		)
		(property "Datasheet" "https://ecsxtal.com/store/pdf/ECS-2016MV.pdf"
			(at 0 0 180)
			(layer "F.Fab")
			(hide yes)
			(effects
				(font
					(size 1.27 1.27)
					(thickness 0.15)
				)
			)
		)
		(property "Description" "Oscillator, 25 MHz, HCMOS, SMD, 2mm x 1.6mm, MultiVolt ECS-2016MV Series"
			(at 0 0 180)
			(layer "F.Fab")
			(hide yes)
			(effects
				(font
					(size 1.27 1.27)
					(thickness 0.15)
				)
			)
		)
		(property "Author" "Antmicro"
			(at 444.4336 234.6914 0)
			(layer "F.Fab")
			(hide yes)
			(effects
				(font
					(size 1 1)
					(thickness 0.15)
				)
			)
		)
		(property "License" "Apache-2.0"
			(at 444.4336 234.6914 0)
			(layer "F.Fab")
			(hide yes)
			(effects
				(font
					(size 1 1)
					(thickness 0.15)
				)
			)
		)
		(property "MPN" "ECS-2016MV-250-CN-TR"
			(at 444.4336 234.6914 0)
			(layer "F.Fab")
			(hide yes)
			(effects
				(font
					(size 1 1)
					(thickness 0.15)
				)
			)
		)
		(property "Manufacturer" "ECS Inc. International"
			(at 444.4336 234.6914 0)
			(layer "F.Fab")
			(hide yes)
			(effects
				(font
					(size 1 1)
					(thickness 0.15)
				)
			)
		)
		(property "Public" ""
			(at 444.4336 234.6914 0)
			(layer "F.Fab")
			(hide yes)
			(effects
				(font
					(size 1 1)
					(thickness 0.15)
				)
			)
		)
		(property "Val" "25 MHz"
			(at 444.4336 234.6914 0)
			(layer "F.Fab")
			(hide yes)
			(effects
				(font
					(size 1 1)
					(thickness 0.15)
				)
			)
		)
		(sheetname "/Ethernet/")
		(sheetfile "ethernet.kicad_sch")
		(attr smd)
		(fp_line
			(start 0.95 0.4)
			(end 0.95 -0.4)
			(stroke
				(width 0.15)
				(type solid)
			)
			(layer "F.SilkS")
		)
		(fp_line
			(start -0.4 1.15)
			(end 0.4 1.15)
			(stroke
				(width 0.15)
				(type solid)
			)
			(layer "F.SilkS")
		)
		(fp_line
			(start -0.4 -1.15)
			(end 0.4 -1.15)
			(stroke
				(width 0.15)
				(type solid)
			)
			(layer "F.SilkS")
		)
		(fp_line
			(start -0.95 0.4)
			(end -0.95 -0.4)
			(stroke
				(width 0.15)
				(type solid)
			)
			(layer "F.SilkS")
		)
		(fp_circle
			(center -0.95 -1.15)
			(end -0.9 -1.15)
			(stroke
				(width 0.15)
				(type solid)
			)
			(fill yes)
			(layer "F.SilkS")
		)
		(fp_rect
			(start -1.05 -1.25)
			(end 1.05 1.24)
			(stroke
				(width 0.05)
				(type solid)
			)
			(fill no)
			(layer "F.CrtYd")
		)
		(fp_rect
			(start -0.85 -1.054)
			(end 0.852 1.054)
			(stroke
				(width 0.15)
				(type solid)
			)
			(fill no)
			(layer "F.Fab")
		)
		(fp_text user "${REFERENCE}"
			(at -1.05 3.4 180)
			(layer "F.Fab")
			(effects
				(font
					(size 0.7 0.7)
					(thickness 0.15)
				)
				(justify left bottom)
			)
		)
		(fp_text user "Author: Antmicro"
			(at -1.05 4.6 180)
			(layer "F.Fab")
			(effects
				(font
					(size 0.7 0.7)
					(thickness 0.15)
				)
				(justify left bottom)
			)
		)
		(fp_text user "License: Apache-2.0"
			(at -1.05 5.8 180)
			(layer "F.Fab")
			(effects
				(font
					(size 0.7 0.7)
					(thickness 0.15)
				)
				(justify left bottom)
			)
		)
		(pad "1" smd rect
			(at -0.486 -0.637 180)
			(size 0.6858 0.7874)
			(layers "F.Cu" "F.Mask" "F.Paste")
			(net 50 "+3V3")
			(pinfunction "EN")
			(pintype "input")
		)
		(pad "2" smd rect
			(at -0.486 0.636 180)
			(size 0.6858 0.7874)
			(layers "F.Cu" "F.Mask" "F.Paste")
			(net 417 "GND")
			(pinfunction "GND")
			(pintype "power_in")
		)
		(pad "3" smd rect
			(at 0.487 0.636 180)
			(size 0.6858 0.7874)
			(layers "F.Cu" "F.Mask" "F.Paste")
			(net 13 "/Ethernet/X_I")
			(pinfunction "OUT")
			(pintype "output")
		)
		(pad "4" smd rect
			(at 0.487 -0.637 180)
			(size 0.6858 0.7874)
			(layers "F.Cu" "F.Mask" "F.Paste")
			(net 50 "+3V3")
			(pinfunction "VDD")
			(pintype "power_in")
		)
	)
	(footprint "antmicro-footprints:TP_SMD_0.75mm"
		(layer "F.Cu")
		(at 223.3 138.75)
		(property "Reference" "TP3"
			(at 0 -0.6 0)
			(layer "F.SilkS")
			(hide yes)
			(effects
				(font
					(size 0.7 0.7)
					(thickness 0.15)
				)
				(justify left bottom)
			)
		)
		(property "Value" "TP_0.75mm_SMD"
			(at 0 1.2 0)
			(layer "F.Fab")
			(hide yes)
			(effects
				(font
					(size 0.7 0.7)
					(thickness 0.15)
				)
				(justify left bottom)
			)
		)
		(property "Description" "SMT test point"
			(at 0 0 0)
			(layer "F.Fab")
			(hide yes)
			(effects
				(font
					(size 1.27 1.27)
					(thickness 0.15)
				)
			)
		)
		(property "Author" "Antmicro"
			(at 0 0 0)
			(layer "F.Fab")
			(hide yes)
			(effects
				(font
					(size 1 1)
					(thickness 0.15)
				)
			)
		)
		(property "License" "Apache-2.0"
			(at 0 0 0)
			(layer "F.Fab")
			(hide yes)
			(effects
				(font
					(size 1 1)
					(thickness 0.15)
				)
			)
		)
		(property "MPN" ""
			(at 0 0 0)
			(layer "F.Fab")
			(hide yes)
			(effects
				(font
					(size 1 1)
					(thickness 0.15)
				)
			)
		)
		(property "Manufacturer" ""
			(at 0 0 0)
			(layer "F.Fab")
			(hide yes)
			(effects
				(font
					(size 1 1)
					(thickness 0.15)
				)
			)
		)
		(property "Public" "False"
			(at 0 0 0)
			(layer "F.Fab")
			(hide yes)
			(effects
				(font
					(size 1 1)
					(thickness 0.15)
				)
			)
		)
		(sheetname "/WiFi_Bluetooth/")
		(sheetfile "wifi_bt.kicad_sch")
		(attr exclude_from_pos_files exclude_from_bom)
		(fp_circle
			(center 0 0)
			(end 0.475 0)
			(stroke
				(width 0.05)
				(type default)
			)
			(fill no)
			(layer "F.CrtYd")
		)
		(fp_text user "License: Apache-2.0"
			(at -0.4 5.101 0)
			(layer "F.Fab")
			(effects
				(font
					(size 0.7 0.7)
					(thickness 0.15)
				)
				(justify left bottom)
			)
		)
		(fp_text user "Author: Antmicro"
			(at -0.4 3.901 0)
			(layer "F.Fab")
			(effects
				(font
					(size 0.7 0.7)
					(thickness 0.15)
				)
				(justify left bottom)
			)
		)
		(fp_text user "${REFERENCE}"
			(at -0.4 2.7 0)
			(layer "F.Fab")
			(effects
				(font
					(size 0.7 0.7)
					(thickness 0.15)
				)
				(justify left bottom)
			)
		)
		(pad "1" smd circle
			(at 0 0)
			(size 0.75 0.75)
			(layers "F.Cu" "F.Mask")
			(net 621 "Net-(U26A-RF_SW_CTRL_5)")
			(pinfunction "1")
			(pintype "passive")
		)
	)
	(footprint "antmicro-footprints:LED_0603_1608Metric_G"
		(layer "F.Cu")
		(at 182.8 154.8 180)
		(descr "LED SMD 0603 Green")
		(tags "LED SMD 0603 Green")
		(property "Reference" "D5"
			(at -4.1 -0.025 0)
			(layer "F.SilkS")
			(effects
				(font
					(size 0.7 0.7)
					(thickness 0.15)
				)
				(justify right top)
			)
		)
		(property "Value" "LED_G_0603_LTST-C190GKT"
			(at -0.001 1.599 0)
			(layer "F.Fab")
			(hide yes)
			(effects
				(font
					(size 0.7 0.7)
					(thickness 0.15)
				)
				(justify right top)
			)
		)
		(property "Datasheet" "https://media.digikey.com/pdf/Data%20Sheets/Lite-On%20PDFs/LTST-C190GKT.pdf"
			(at 0 0 0)
			(layer "F.Fab")
			(hide yes)
			(effects
				(font
					(size 1.27 1.27)
					(thickness 0.15)
				)
			)
		)
		(property "Description" "LED, Green, SMD, 0603, 20 mA, 2.1 V, 569 nm"
			(at 0 0 0)
			(layer "F.Fab")
			(hide yes)
			(effects
				(font
					(size 1.27 1.27)
					(thickness 0.15)
				)
			)
		)
		(property "Author" "Antmicro"
			(at 0 0 0)
			(layer "F.Fab")
			(hide yes)
			(effects
				(font
					(size 1 1)
					(thickness 0.15)
				)
			)
		)
		(property "Color" "Green"
			(at 0 0 0)
			(layer "F.Fab")
			(hide yes)
			(effects
				(font
					(size 1 1)
					(thickness 0.15)
				)
			)
		)
		(property "License" "Apache-2.0"
			(at 0 0 0)
			(layer "F.Fab")
			(hide yes)
			(effects
				(font
					(size 1 1)
					(thickness 0.15)
				)
			)
		)
		(property "MPN" "LTST-C190GKT"
			(at 0 0 0)
			(layer "F.Fab")
			(hide yes)
			(effects
				(font
					(size 1 1)
					(thickness 0.15)
				)
			)
		)
		(property "Manufacturer" "Lite-On"
			(at 0 0 0)
			(layer "F.Fab")
			(hide yes)
			(effects
				(font
					(size 1 1)
					(thickness 0.15)
				)
			)
		)
		(property "Public" ""
			(at 0 0 0)
			(layer "F.Fab")
			(hide yes)
			(effects
				(font
					(size 1 1)
					(thickness 0.15)
				)
			)
		)
		(property "VSD_class" "LED"
			(at 0 0 0)
			(layer "F.Fab")
			(hide yes)
			(effects
				(font
					(size 1 1)
					(thickness 0.15)
				)
			)
		)
		(sheetname "/Supply/")
		(sheetfile "supply.kicad_sch")
		(attr smd)
		(fp_line
			(start 0.22 0.35)
			(end -0.22 0.35)
			(stroke
				(width 0.15)
				(type solid)
			)
			(layer "F.SilkS")
		)
		(fp_line
			(start 0.22 -0.35)
			(end -0.22 -0.35)
			(stroke
				(width 0.15)
				(type solid)
			)
			(layer "F.SilkS")
		)
		(fp_line
			(start 0.105328 0.201008)
			(end 0.105328 -0.198992)
			(stroke
				(width 0.1)
				(type solid)
			)
			(layer "F.SilkS")
		)
		(fp_line
			(start 0.105328 0.201008)
			(end -0.094672 0.001008)
			(stroke
				(width 0.1)
				(type solid)
			)
			(layer "F.SilkS")
		)
		(fp_line
			(start 0.105328 0.001008)
			(end 0.24 0.001)
			(stroke
				(width 0.1)
				(type solid)
			)
			(layer "F.SilkS")
		)
		(fp_line
			(start -0.094672 0.201008)
			(end -0.094672 -0.198992)
			(stroke
				(width 0.1)
				(type solid)
			)
			(layer "F.SilkS")
		)
		(fp_line
			(start -0.094672 0.001008)
			(end 0.105328 -0.198992)
			(stroke
				(width 0.1)
				(type solid)
			)
			(layer "F.SilkS")
		)
		(fp_line
			(start -0.094672 0.001008)
			(end -0.24 0.001008)
			(stroke
				(width 0.1)
				(type solid)
			)
			(layer "F.SilkS")
		)
		(fp_line
			(start -1.18 -0.319)
			(end -1.18 0.321)
			(stroke
				(width 0.15)
				(type solid)
			)
			(layer "F.SilkS")
		)
		(fp_rect
			(start 1.25 0.65)
			(end -1.25 -0.65)
			(stroke
				(width 0.05)
				(type solid)
			)
			(fill no)
			(layer "F.CrtYd")
		)
		(fp_line
			(start 0.599 0)
			(end 0.201 0)
			(stroke
				(width 0.15)
				(type solid)
			)
			(layer "F.Fab")
		)
		(fp_line
			(start 0.201 0.2)
			(end 0.201 0)
			(stroke
				(width 0.15)
				(type solid)
			)
			(layer "F.Fab")
		)
		(fp_line
			(start 0.201 0)
			(end 0.201 -0.202)
			(stroke
				(width 0.15)
				(type solid)
			)
			(layer "F.Fab")
		)
		(fp_line
			(start 0.201 -0.202)
			(end -0.101 0)
			(stroke
				(width 0.15)
				(type solid)
			)
			(layer "F.Fab")
		)
		(fp_line
			(start -0.101 0)
			(end 0.201 0.2)
			(stroke
				(width 0.15)
				(type solid)
			)
			(layer "F.Fab")
		)
		(fp_line
			(start -0.199 0.2)
			(end -0.199 0.1)
			(stroke
				(width 0.15)
				(type solid)
			)
			(layer "F.Fab")
		)
		(fp_line
			(start -0.199 0)
			(end -0.597 0)
			(stroke
				(width 0.15)
				(type solid)
			)
			(layer "F.Fab")
		)
		(fp_line
			(start -0.199 -0.202)
			(end -0.199 0.1)
			(stroke
				(width 0.15)
				(type solid)
			)
			(layer "F.Fab")
		)
		(fp_rect
			(start 0.848 0.4)
			(end -0.85 -0.402)
			(stroke
				(width 0.15)
				(type solid)
			)
			(fill no)
			(layer "F.Fab")
		)
		(fp_text user "${REFERENCE}"
			(at -1.4224 5.999 180)
			(layer "F.Fab")
			(effects
				(font
					(size 0.7 0.7)
					(thickness 0.15)
				)
				(justify left bottom)
			)
		)
		(fp_text user "License: Apache-2.0"
			(at -1.4224 3.599 180)
			(layer "F.Fab")
			(effects
				(font
					(size 0.7 0.7)
					(thickness 0.15)
				)
				(justify left bottom)
			)
		)
		(fp_text user "Author: Antmicro"
			(at -1.4224 4.799 180)
			(layer "F.Fab")
			(effects
				(font
					(size 0.7 0.7)
					(thickness 0.15)
				)
				(justify left bottom)
			)
		)
		(pad "1" smd roundrect
			(at -0.7 0)
			(size 0.8 1)
			(layers "F.Cu" "F.Mask" "F.Paste")
			(roundrect_rratio 0.2)
			(net 230 "~{PG}")
			(pinfunction "C")
			(pintype "passive")
		)
		(pad "2" smd roundrect
			(at 0.7 0)
			(size 0.8 1)
			(layers "F.Cu" "F.Mask" "F.Paste")
			(roundrect_rratio 0.2)
			(net 650 "Net-(D5-A)")
			(pinfunction "A")
			(pintype "passive")
		)
	)
)
